# T6G (Grand Teton) — schematic netlist excerpt (pin names and nets, part order shuffled) for the footprints in the layout excerpt that follows; sources: Cadence DE-HDL packaged netlist, KiCad conversion of 04192023_DAF0TMB3IC0_F0TG_MB_C_brd_V02_OCP.brd

R1463  Q_RES  1K 1% CHIP  pkg 0201LF  page 185 : A = P1V8_CPU1_RT_1D ; B = SMB_RT_CPU1_P3_ROM_MUX_1D_SCL
R5102  Q_RES  49.9 1% CHIP  pkg 0402LF  page 28 : A = XTAL_CPU0_X48M_X2 ; B = XTAL_CPU0_X48M_X2_R
PR2522  Q_RES  1 1% CHIP  pkg 0402LF  page 266 : A = P12V_HSC_SENSE2_P ; B = P12V_HSC_SENSE2_R3_P

(kicad_pcb
	(version 20260206)
	(generator "pcbnew")
	(generator_version "10.0")
	(general
		(thickness 1.6)
		(legacy_teardrops no)
	)
	(paper "A4")
	(title_block
		(title "04192023_DAF0TMB3IC0_F0TG_MB_C_brd_V02_OCP.brd")
		(comment 1 "Grand Teton / footprints 7262-7264 of 8354")
	)
	(layers
		(0 "F.Cu" signal "TOP")
		(4 "In1.Cu" signal "GND")
		(6 "In2.Cu" signal "IN1")
		(8 "In3.Cu" signal "GND1")
		(10 "In4.Cu" signal "IN2")
		(12 "In5.Cu" signal "GND2")
		(14 "In6.Cu" signal "IN3")
		(16 "In7.Cu" signal "GND3")
		(18 "In8.Cu" signal "VCC")
		(20 "In9.Cu" signal "VCC1")
		(22 "In10.Cu" signal "GND4")
		(24 "In11.Cu" signal "IN4")
		(26 "In12.Cu" signal "GND5")
		(28 "In13.Cu" signal "IN5")
		(30 "In14.Cu" signal "GND6")
		(32 "In15.Cu" signal "IN6")
		(34 "In16.Cu" signal "GND7")
		(2 "B.Cu" signal "BOTTOM")
		(9 "F.Adhes" user "F.Adhesive")
		(11 "B.Adhes" user "B.Adhesive")
		(13 "F.Paste" user "Package Geometry/Pastemask Top")
		(15 "B.Paste" user "Package Geometry/Pastemask Bottom")
		(5 "F.SilkS" user "Ref Des/Silkscreen Top")
		(7 "B.SilkS" user "Ref Des/Silkscreen Bottom")
		(1 "F.Mask" user "Board Geometry/Soldermask Top")
		(3 "B.Mask" user "Board Geometry/Soldermask Bottom")
		(17 "Dwgs.User" user "User.Drawings")
		(19 "Cmts.User" user "User.Comments")
		(21 "Eco1.User" user "User.Eco1")
		(23 "Eco2.User" user "User.Eco2")
		(25 "Edge.Cuts" user "Board Geometry/Outline")
		(27 "Margin" user)
		(31 "F.CrtYd" user "Package Geometry/Place Bound Top")
		(29 "B.CrtYd" user "Package Geometry/Place Bound Bottom")
		(35 "F.Fab" user "Ref Des/Assembly Top")
		(33 "B.Fab" user "Ref Des/Assembly Bottom")
	)
	(footprint ""
		(layer "B.Cu")
		(at 206.429356 -380.206504 180)
		(property "Reference" "PR2522"
			(at 0 0 0)
			(layer "B.SilkS")
			(hide yes)
			(effects
				(font
					(size 1.27 1.27)
				)
				(justify mirror)
			)
		)
		(property "Value" ""
			(at 0 0 0)
			(layer "B.Fab")
			(effects
				(font
					(size 1.27 1.27)
				)
				(justify mirror)
			)
		)
		(duplicate_pad_numbers_are_jumpers no)
		(fp_line
			(start 0.7874 0.4064)
			(end 0.7874 -0.4064)
			(stroke
				(width 0.1524)
				(type default)
			)
			(layer "B.SilkS")
		)
		(fp_line
			(start 0.7874 -0.4064)
			(end -0.7874 -0.4064)
			(stroke
				(width 0.1524)
				(type default)
			)
			(layer "B.SilkS")
		)
		(fp_line
			(start -0.7874 0.4064)
			(end 0.7874 0.4064)
			(stroke
				(width 0.1524)
				(type default)
			)
			(layer "B.SilkS")
		)
		(fp_line
			(start -0.7874 -0.4064)
			(end -0.7874 0.4064)
			(stroke
				(width 0.1524)
				(type default)
			)
			(layer "B.SilkS")
		)
		(fp_line
			(start 0.67945 0.3048)
			(end 0.67945 -0.305054)
			(stroke
				(width 0.1)
				(type default)
			)
			(layer "B.Fab")
		)
		(fp_line
			(start 0.67945 -0.305054)
			(end 0.12065 -0.305054)
			(stroke
				(width 0.1)
				(type default)
			)
			(layer "B.Fab")
		)
		(fp_line
			(start 0.12065 0.3048)
			(end 0.67945 0.3048)
			(stroke
				(width 0.1)
				(type default)
			)
			(layer "B.Fab")
		)
		(fp_line
			(start 0.12065 0.2794)
			(end 0.12065 0.3048)
			(stroke
				(width 0.1)
				(type default)
			)
			(layer "B.Fab")
		)
		(fp_line
			(start 0.12065 -0.2794)
			(end -0.12065 -0.2794)
			(stroke
				(width 0.1)
				(type default)
			)
			(layer "B.Fab")
		)
		(fp_line
			(start 0.12065 -0.305054)
			(end 0.12065 -0.2794)
			(stroke
				(width 0.1)
				(type default)
			)
			(layer "B.Fab")
		)
		(fp_line
			(start -0.120396 0.3048)
			(end -0.120396 0.2794)
			(stroke
				(width 0.1)
				(type default)
			)
			(layer "B.Fab")
		)
		(fp_line
			(start -0.120396 0.2794)
			(end 0.12065 0.2794)
			(stroke
				(width 0.1)
				(type default)
			)
			(layer "B.Fab")
		)
		(fp_line
			(start -0.12065 -0.2794)
			(end -0.12065 -0.3048)
			(stroke
				(width 0.1)
				(type default)
			)
			(layer "B.Fab")
		)
		(fp_line
			(start -0.12065 -0.3048)
			(end -0.67945 -0.3048)
			(stroke
				(width 0.1)
				(type default)
			)
			(layer "B.Fab")
		)
		(fp_line
			(start -0.67945 0.3048)
			(end -0.120396 0.3048)
			(stroke
				(width 0.1)
				(type default)
			)
			(layer "B.Fab")
		)
		(fp_line
			(start -0.67945 -0.3048)
			(end -0.67945 0.3048)
			(stroke
				(width 0.1)
				(type default)
			)
			(layer "B.Fab")
		)
		(pad "1" smd circle
			(at 0.40005 0)
			(size 0 0)
			(layers "B.Cu" "B.Mask" "B.Paste")
			(net "P12V_HSC_SENSE2_P")
		)
		(pad "2" smd circle
			(at -0.40005 0)
			(size 0 0)
			(layers "B.Cu" "B.Mask" "B.Paste")
			(net "P12V_HSC_SENSE2_R3_P")
		)
	)
	(footprint ""
		(layer "B.Cu")
		(at 397.935958 -313.477148)
		(property "Reference" "R5102"
			(at 0 0 0)
			(layer "B.SilkS")
			(hide yes)
			(effects
				(font
					(size 1.27 1.27)
				)
				(justify mirror)
			)
		)
		(property "Value" ""
			(at 0 0 0)
			(layer "B.Fab")
			(effects
				(font
					(size 1.27 1.27)
				)
				(justify mirror)
			)
		)
		(duplicate_pad_numbers_are_jumpers no)
		(fp_line
			(start -0.7874 -0.4064)
			(end -0.7874 0.4064)
			(stroke
				(width 0.1524)
				(type default)
			)
			(layer "B.SilkS")
		)
		(fp_line
			(start -0.7874 0.4064)
			(end 0.7874 0.4064)
			(stroke
				(width 0.1524)
				(type default)
			)
			(layer "B.SilkS")
		)
		(fp_line
			(start 0.7874 -0.4064)
			(end -0.7874 -0.4064)
			(stroke
				(width 0.1524)
				(type default)
			)
			(layer "B.SilkS")
		)
		(fp_line
			(start 0.7874 0.4064)
			(end 0.7874 -0.4064)
			(stroke
				(width 0.1524)
				(type default)
			)
			(layer "B.SilkS")
		)
		(fp_line
			(start -0.67945 -0.3048)
			(end -0.67945 0.3048)
			(stroke
				(width 0.1)
				(type default)
			)
			(layer "B.Fab")
		)
		(fp_line
			(start -0.67945 0.3048)
			(end -0.120396 0.3048)
			(stroke
				(width 0.1)
				(type default)
			)
			(layer "B.Fab")
		)
		(fp_line
			(start -0.12065 -0.3048)
			(end -0.67945 -0.3048)
			(stroke
				(width 0.1)
				(type default)
			)
			(layer "B.Fab")
		)
		(fp_line
			(start -0.12065 -0.2794)
			(end -0.12065 -0.3048)
			(stroke
				(width 0.1)
				(type default)
			)
			(layer "B.Fab")
		)
		(fp_line
			(start -0.120396 0.2794)
			(end 0.12065 0.2794)
			(stroke
				(width 0.1)
				(type default)
			)
			(layer "B.Fab")
		)
		(fp_line
			(start -0.120396 0.3048)
			(end -0.120396 0.2794)
			(stroke
				(width 0.1)
				(type default)
			)
			(layer "B.Fab")
		)
		(fp_line
			(start 0.12065 -0.305054)
			(end 0.12065 -0.2794)
			(stroke
				(width 0.1)
				(type default)
			)
			(layer "B.Fab")
		)
		(fp_line
			(start 0.12065 -0.2794)
			(end -0.12065 -0.2794)
			(stroke
				(width 0.1)
				(type default)
			)
			(layer "B.Fab")
		)
		(fp_line
			(start 0.12065 0.2794)
			(end 0.12065 0.3048)
			(stroke
				(width 0.1)
				(type default)
			)
			(layer "B.Fab")
		)
		(fp_line
			(start 0.12065 0.3048)
			(end 0.67945 0.3048)
			(stroke
				(width 0.1)
				(type default)
			)
			(layer "B.Fab")
		)
		(fp_line
			(start 0.67945 -0.305054)
			(end 0.12065 -0.305054)
			(stroke
				(width 0.1)
				(type default)
			)
			(layer "B.Fab")
		)
		(fp_line
			(start 0.67945 0.3048)
			(end 0.67945 -0.305054)
			(stroke
				(width 0.1)
				(type default)
			)
			(layer "B.Fab")
		)
		(pad "1" smd circle
			(at 0.40005 0 180)
			(size 0 0)
			(layers "B.Cu" "B.Mask" "B.Paste")
			(net "XTAL_CPU0_X48M_X2")
		)
		(pad "2" smd circle
			(at -0.40005 0 180)
			(size 0 0)
			(layers "B.Cu" "B.Mask" "B.Paste")
			(net "XTAL_CPU0_X48M_X2_R")
		)
	)
	(footprint ""
		(layer "B.Cu")
		(at 169.2148 -421.277796 -90)
		(property "Reference" "R1463"
			(at 0 0 90)
			(layer "B.SilkS")
			(hide yes)
			(effects
				(font
					(size 1.27 1.27)
				)
				(justify mirror)
			)
		)
		(property "Value" ""
			(at 0 0 90)
			(layer "B.Fab")
			(effects
				(font
					(size 1.27 1.27)
				)
				(justify mirror)
			)
		)
		(duplicate_pad_numbers_are_jumpers no)
		(fp_line
			(start -0.32512 0.175006)
			(end 0.32512 0.175006)
			(stroke
				(width 0.1)
				(type default)
			)
			(layer "B.Fab")
		)
		(fp_line
			(start 0.32512 0.175006)
			(end 0.32512 -0.175006)
			(stroke
				(width 0.1)
				(type default)
			)
			(layer "B.Fab")
		)
		(fp_line
			(start -0.32512 -0.175006)
			(end -0.32512 0.175006)
			(stroke
				(width 0.1)
				(type default)
			)
			(layer "B.Fab")
		)
		(fp_line
			(start 0.32512 -0.175006)
			(end -0.32512 -0.175006)
			(stroke
				(width 0.1)
				(type default)
			)
			(layer "B.Fab")
		)
		(pad "1" smd rect
			(at 0.2667 0 90)
			(size 0.3048 0.381)
			(layers "B.Cu" "B.Mask" "B.Paste")
			(net "P1V8_CPU1_RT_1D")
		)
		(pad "2" smd rect
			(at -0.2667 0 270)
			(size 0.3048 0.381)
			(layers "B.Cu" "B.Mask" "B.Paste")
			(net "SMB_RT_CPU1_P3_ROM_MUX_1D_SCL")
		)
	)
)
